# S9S_MB_2U (Grand Teton) — schematic netlist excerpt (pin names and nets, part order shuffled) for the footprints in the layout excerpt that follows; sources: Cadence DE-HDL packaged netlist, KiCad conversion of 03242023_DA0F0TMBIJ0_F0T_Motherboard_J_brd_V01_OCP.brd

R2899  Q_RES  0 5% CHIP  pkg 0402LF  page 234 : A = SMB_BMC_GPU_EN ; B = SMB_BMC_GPU_EN_R1
R554  Q_RES  0 5% CHIP  pkg 0402LF  page 209 : A = CLK_100M_CK440_PCH_EXTCLK_R_DN ; B = CLK_100M_CK440_PCH_EXTCLK_DN

(kicad_pcb
	(version 20260206)
	(generator "pcbnew")
	(generator_version "10.0")
	(general
		(thickness 1.6)
		(legacy_teardrops no)
	)
	(paper "A4")
	(title_block
		(title "03242023_DA0F0TMBIJ0_F0T_Motherboard_J_brd_V01_OCP.brd")
		(comment 1 "Grand Teton / footprints 3260-3261 of 6105")
	)
	(layers
		(0 "F.Cu" signal "TOP")
		(4 "In1.Cu" signal "GND")
		(6 "In2.Cu" signal "IN1")
		(8 "In3.Cu" signal "GND1")
		(10 "In4.Cu" signal "IN2")
		(12 "In5.Cu" signal "GND2")
		(14 "In6.Cu" signal "IN3")
		(16 "In7.Cu" signal "GND3")
		(18 "In8.Cu" signal "VCC")
		(20 "In9.Cu" signal "VCC1")
		(22 "In10.Cu" signal "GND4")
		(24 "In11.Cu" signal "IN4")
		(26 "In12.Cu" signal "GND5")
		(28 "In13.Cu" signal "IN5")
		(30 "In14.Cu" signal "GND6")
		(32 "In15.Cu" signal "IN6")
		(34 "In16.Cu" signal "GND7")
		(2 "B.Cu" signal "BOTTOM")
		(9 "F.Adhes" user "F.Adhesive")
		(11 "B.Adhes" user "B.Adhesive")
		(13 "F.Paste" user "Package Geometry/Pastemask Top")
		(15 "B.Paste" user "Package Geometry/Pastemask Bottom")
		(5 "F.SilkS" user "Ref Des/Silkscreen Top")
		(7 "B.SilkS" user "Ref Des/Silkscreen Bottom")
		(1 "F.Mask" user "Board Geometry/Soldermask Top")
		(3 "B.Mask" user "Board Geometry/Soldermask Bottom")
		(17 "Dwgs.User" user "User.Drawings")
		(19 "Cmts.User" user "User.Comments")
		(21 "Eco1.User" user "User.Eco1")
		(23 "Eco2.User" user "User.Eco2")
		(25 "Edge.Cuts" user "Board Geometry/Outline")
		(27 "Margin" user)
		(31 "F.CrtYd" user "Package Geometry/Place Bound Top")
		(29 "B.CrtYd" user "Package Geometry/Place Bound Bottom")
		(35 "F.Fab" user "Ref Des/Assembly Top")
		(33 "B.Fab" user "Ref Des/Assembly Bottom")
	)
	(footprint ""
		(layer "F.Cu")
		(at 258.192524 -108.154216 90)
		(property "Reference" "R554"
			(at 0 0 90)
			(layer "F.SilkS")
			(hide yes)
			(effects
				(font
					(size 1.27 1.27)
				)
			)
		)
		(property "Value" ""
			(at 0 0 90)
			(layer "F.Fab")
			(effects
				(font
					(size 1.27 1.27)
				)
			)
		)
		(duplicate_pad_numbers_are_jumpers no)
		(fp_line
			(start 0.7874 -0.4064)
			(end 0.7874 0.4064)
			(stroke
				(width 0.1524)
				(type default)
			)
			(layer "F.SilkS")
		)
		(fp_line
			(start -0.7874 -0.4064)
			(end 0.7874 -0.4064)
			(stroke
				(width 0.1524)
				(type default)
			)
			(layer "F.SilkS")
		)
		(fp_line
			(start 0.7874 0.4064)
			(end -0.7874 0.4064)
			(stroke
				(width 0.1524)
				(type default)
			)
			(layer "F.SilkS")
		)
		(fp_line
			(start -0.7874 0.4064)
			(end -0.7874 -0.4064)
			(stroke
				(width 0.1524)
				(type default)
			)
			(layer "F.SilkS")
		)
		(fp_line
			(start -0.12065 -0.305054)
			(end -0.12065 -0.2794)
			(stroke
				(width 0.1)
				(type default)
			)
			(layer "F.Fab")
		)
		(fp_line
			(start -0.67945 -0.305054)
			(end -0.12065 -0.305054)
			(stroke
				(width 0.1)
				(type default)
			)
			(layer "F.Fab")
		)
		(fp_line
			(start 0.67945 -0.3048)
			(end 0.67945 0.3048)
			(stroke
				(width 0.1)
				(type default)
			)
			(layer "F.Fab")
		)
		(fp_line
			(start 0.12065 -0.3048)
			(end 0.67945 -0.3048)
			(stroke
				(width 0.1)
				(type default)
			)
			(layer "F.Fab")
		)
		(fp_line
			(start 0.12065 -0.2794)
			(end 0.12065 -0.3048)
			(stroke
				(width 0.1)
				(type default)
			)
			(layer "F.Fab")
		)
		(fp_line
			(start -0.12065 -0.2794)
			(end 0.12065 -0.2794)
			(stroke
				(width 0.1)
				(type default)
			)
			(layer "F.Fab")
		)
		(fp_line
			(start 0.120396 0.2794)
			(end -0.12065 0.2794)
			(stroke
				(width 0.1)
				(type default)
			)
			(layer "F.Fab")
		)
		(fp_line
			(start -0.12065 0.2794)
			(end -0.12065 0.3048)
			(stroke
				(width 0.1)
				(type default)
			)
			(layer "F.Fab")
		)
		(fp_line
			(start 0.67945 0.3048)
			(end 0.120396 0.3048)
			(stroke
				(width 0.1)
				(type default)
			)
			(layer "F.Fab")
		)
		(fp_line
			(start 0.120396 0.3048)
			(end 0.120396 0.2794)
			(stroke
				(width 0.1)
				(type default)
			)
			(layer "F.Fab")
		)
		(fp_line
			(start -0.12065 0.3048)
			(end -0.67945 0.3048)
			(stroke
				(width 0.1)
				(type default)
			)
			(layer "F.Fab")
		)
		(fp_line
			(start -0.67945 0.3048)
			(end -0.67945 -0.305054)
			(stroke
				(width 0.1)
				(type default)
			)
			(layer "F.Fab")
		)
		(pad "1" smd circle
			(at -0.40005 0 90)
			(size 0 0)
			(layers "F.Cu" "F.Mask" "F.Paste")
			(net "CLK_100M_CK440_PCH_EXTCLK_R_DN")
		)
		(pad "2" smd circle
			(at 0.40005 0 90)
			(size 0 0)
			(layers "F.Cu" "F.Mask" "F.Paste")
			(net "CLK_100M_CK440_PCH_EXTCLK_DN")
		)
	)
	(footprint ""
		(layer "F.Cu")
		(at 39.80688 -435.955948)
		(property "Reference" "R2899"
			(at 0 0 0)
			(layer "F.SilkS")
			(hide yes)
			(effects
				(font
					(size 1.27 1.27)
				)
			)
		)
		(property "Value" ""
			(at 0 0 0)
			(layer "F.Fab")
			(effects
				(font
					(size 1.27 1.27)
				)
			)
		)
		(duplicate_pad_numbers_are_jumpers no)
		(fp_line
			(start -0.7874 -0.4064)
			(end 0.7874 -0.4064)
			(stroke
				(width 0.1524)
				(type default)
			)
			(layer "F.SilkS")
		)
		(fp_line
			(start -0.7874 0.4064)
			(end -0.7874 -0.4064)
			(stroke
				(width 0.1524)
				(type default)
			)
			(layer "F.SilkS")
		)
		(fp_line
			(start 0.7874 -0.4064)
			(end 0.7874 0.4064)
			(stroke
				(width 0.1524)
				(type default)
			)
			(layer "F.SilkS")
		)
		(fp_line
			(start 0.7874 0.4064)
			(end -0.7874 0.4064)
			(stroke
				(width 0.1524)
				(type default)
			)
			(layer "F.SilkS")
		)
		(fp_line
			(start -0.67945 -0.305054)
			(end -0.12065 -0.305054)
			(stroke
				(width 0.1)
				(type default)
			)
			(layer "F.Fab")
		)
		(fp_line
			(start -0.67945 0.3048)
			(end -0.67945 -0.305054)
			(stroke
				(width 0.1)
				(type default)
			)
			(layer "F.Fab")
		)
		(fp_line
			(start -0.12065 -0.305054)
			(end -0.12065 -0.2794)
			(stroke
				(width 0.1)
				(type default)
			)
			(layer "F.Fab")
		)
		(fp_line
			(start -0.12065 -0.2794)
			(end 0.12065 -0.2794)
			(stroke
				(width 0.1)
				(type default)
			)
			(layer "F.Fab")
		)
		(fp_line
			(start -0.12065 0.2794)
			(end -0.12065 0.3048)
			(stroke
				(width 0.1)
				(type default)
			)
			(layer "F.Fab")
		)
		(fp_line
			(start -0.12065 0.3048)
			(end -0.67945 0.3048)
			(stroke
				(width 0.1)
				(type default)
			)
			(layer "F.Fab")
		)
		(fp_line
			(start 0.120396 0.2794)
			(end -0.12065 0.2794)
			(stroke
				(width 0.1)
				(type default)
			)
			(layer "F.Fab")
		)
		(fp_line
			(start 0.120396 0.3048)
			(end 0.120396 0.2794)
			(stroke
				(width 0.1)
				(type default)
			)
			(layer "F.Fab")
		)
		(fp_line
			(start 0.12065 -0.3048)
			(end 0.67945 -0.3048)
			(stroke
				(width 0.1)
				(type default)
			)
			(layer "F.Fab")
		)
		(fp_line
			(start 0.12065 -0.2794)
			(end 0.12065 -0.3048)
			(stroke
				(width 0.1)
				(type default)
			)
			(layer "F.Fab")
		)
		(fp_line
			(start 0.67945 -0.3048)
			(end 0.67945 0.3048)
			(stroke
				(width 0.1)
				(type default)
			)
			(layer "F.Fab")
		)
		(fp_line
			(start 0.67945 0.3048)
			(end 0.120396 0.3048)
			(stroke
				(width 0.1)
				(type default)
			)
			(layer "F.Fab")
		)
		(pad "1" smd circle
			(at -0.40005 0)
			(size 0 0)
			(layers "F.Cu" "F.Mask" "F.Paste")
			(net "SMB_BMC_GPU_EN")
		)
		(pad "2" smd circle
			(at 0.40005 0)
			(size 0 0)
			(layers "F.Cu" "F.Mask" "F.Paste")
			(net "SMB_BMC_GPU_EN_R1")
		)
	)
)
